(kicad_pcb
	(version 20260206)
	(generator "pcbnew")
	(generator_version "10.0")
	(general
		(thickness 1.6)
		(legacy_teardrops no)
	)
	(paper "A4")
	(title_block
		(title "Bryce Canyon_F.DPB_16315-1-OCP.brd")
		(comment 1 "Bryce Canyon / footprints 814-821 of 2223")
	)
	(layers
		(0 "F.Cu" signal "TOP")
		(4 "In1.Cu" signal "L2GND")
		(6 "In2.Cu" signal "L3")
		(8 "In3.Cu" signal "L4GND")
		(10 "In4.Cu" signal "L5")
		(12 "In5.Cu" signal "L6VCC")
		(14 "In6.Cu" signal "L7VCC")
		(16 "In7.Cu" signal "L8")
		(18 "In8.Cu" signal "L9GND")
		(20 "In9.Cu" signal "L10")
		(22 "In10.Cu" signal "L11GND")
		(2 "B.Cu" signal "BOTTOM")
		(9 "F.Adhes" user "F.Adhesive")
		(11 "B.Adhes" user "B.Adhesive")
		(13 "F.Paste" user "Package Geometry/Pastemask Top")
		(15 "B.Paste" user "Package Geometry/Pastemask Bottom")
		(5 "F.SilkS" user "Ref Des/Silkscreen Top")
		(7 "B.SilkS" user "Ref Des/Silkscreen Bottom")
		(1 "F.Mask" user "Board Geometry/Soldermask Top")
		(3 "B.Mask" user "Board Geometry/Soldermask Bottom")
		(17 "Dwgs.User" user "User.Drawings")
		(19 "Cmts.User" user "User.Comments")
		(21 "Eco1.User" user "User.Eco1")
		(23 "Eco2.User" user "User.Eco2")
		(25 "Edge.Cuts" user "Board Geometry/Outline")
		(27 "Margin" user)
		(31 "F.CrtYd" user "Package Geometry/Place Bound Top")
		(29 "B.CrtYd" user "Package Geometry/Place Bound Bottom")
		(35 "F.Fab" user "Ref Des/Assembly Top")
		(33 "B.Fab" user "Ref Des/Assembly Bottom")
	)
	(footprint ""
		(layer "F.Cu")
		(at 440.68873 -284.512258 90)
		(property "Reference" "R586"
			(at 0 0 90)
			(layer "F.SilkS")
			(hide yes)
			(effects
				(font
					(size 1.27 1.27)
				)
			)
		)
		(property "Value" "4K7R2J-2-GP"
			(at 0.064008 -3.993896 90)
			(unlocked yes)
			(layer "F.Fab")
			(hide yes)
			(effects
				(font
					(size 1.016 1.016)
					(thickness 0.1524)
				)
			)
		)
		(property "Device Type" "R402H16"
			(at 0.064008 -5.517896 90)
			(unlocked yes)
			(layer "F.Fab")
			(hide yes)
			(effects
				(font
					(size 1.016 1.016)
					(thickness 0.1524)
				)
			)
		)
		(duplicate_pad_numbers_are_jumpers no)
		(fp_line
			(start 0.508 -0.9398)
			(end -0.508 -0.9398)
			(stroke
				(width 0.1524)
				(type default)
			)
			(layer "F.SilkS")
		)
		(fp_line
			(start -0.508 -0.9398)
			(end -0.508 0.9398)
			(stroke
				(width 0.1524)
				(type default)
			)
			(layer "F.SilkS")
		)
		(fp_rect
			(start -0.508 0.9398)
			(end 0.508 -0.9398)
			(stroke
				(width 0)
				(type default)
			)
			(fill no)
			(layer "F.CrtYd")
		)
		(fp_rect
			(start -0.508 0.9398)
			(end 0.508 -0.9398)
			(stroke
				(width 0)
				(type default)
			)
			(fill no)
			(layer "F.Fab")
		)
		(pad "1" smd custom
			(at 0 -0.4445 90)
			(size 0.1397 0.1397)
			(layers "F.Cu" "F.Mask" "F.Paste")
			(net "DRIVE_B_34_ACT")
			(options
				(clearance outline)
				(anchor circle)
			)
			(primitives
				(gr_poly
					(pts
						(arc
							(start -0.1778 -0.2794)
							(mid -0.249642 -0.249642)
							(end -0.2794 -0.1778)
						)
						(arc
							(start -0.2794 0.1778)
							(mid -0.249642 0.249642)
							(end -0.1778 0.2794)
						)
						(arc
							(start 0.1778 0.2794)
							(mid 0.249642 0.249642)
							(end 0.2794 0.1778)
						)
						(arc
							(start 0.2794 -0.1778)
							(mid 0.249642 -0.249642)
							(end 0.1778 -0.2794)
						)
					)
					(width 0)
					(fill yes)
				)
			)
		)
		(pad "2" smd custom
			(at 0 0.4445 90)
			(size 0.1397 0.1397)
			(layers "F.Cu" "F.Mask" "F.Paste")
			(net "GND")
			(options
				(clearance outline)
				(anchor circle)
			)
			(primitives
				(gr_poly
					(pts
						(arc
							(start -0.1778 -0.2794)
							(mid -0.249642 -0.249642)
							(end -0.2794 -0.1778)
						)
						(arc
							(start -0.2794 0.1778)
							(mid -0.249642 0.249642)
							(end -0.1778 0.2794)
						)
						(arc
							(start 0.1778 0.2794)
							(mid 0.249642 0.249642)
							(end 0.2794 0.1778)
						)
						(arc
							(start 0.2794 -0.1778)
							(mid 0.249642 -0.249642)
							(end 0.1778 -0.2794)
						)
					)
					(width 0)
					(fill yes)
				)
			)
		)
	)
	(footprint ""
		(layer "F.Cu")
		(at 361.369102 -66.842894 180)
		(property "Reference" "C443"
			(at 0 0 180)
			(layer "F.SilkS")
			(hide yes)
			(effects
				(font
					(size 1.27 1.27)
				)
			)
		)
		(property "Value" "SC1U16V3KX-5GP"
			(at 0 -2.8194 180)
			(unlocked yes)
			(layer "F.Fab")
			(hide yes)
			(effects
				(font
					(size 1.016 1.016)
					(thickness 0.1524)
				)
			)
		)
		(property "Device Type" "C603H36"
			(at 0 -4.3434 180)
			(unlocked yes)
			(layer "F.Fab")
			(hide yes)
			(effects
				(font
					(size 1.016 1.016)
					(thickness 0.1524)
				)
			)
		)
		(duplicate_pad_numbers_are_jumpers no)
		(fp_line
			(start 0.508 0)
			(end -0.508 0)
			(stroke
				(width 0.2032)
				(type default)
			)
			(layer "F.SilkS")
		)
		(fp_rect
			(start -0.5842 1.3335)
			(end 0.5842 -1.3335)
			(stroke
				(width 0)
				(type default)
			)
			(fill no)
			(layer "F.CrtYd")
		)
		(fp_rect
			(start -0.5842 1.3335)
			(end 0.5842 -1.3335)
			(stroke
				(width 0)
				(type default)
			)
			(fill no)
			(layer "F.Fab")
		)
		(pad "1" smd custom
			(at 0 -0.762 180)
			(size 0.2159 0.2159)
			(layers "F.Cu" "F.Mask" "F.Paste")
			(net "P5V_HDD31")
			(options
				(clearance outline)
				(anchor circle)
			)
			(primitives
				(gr_poly
					(pts
						(arc
							(start -0.3302 -0.4318)
							(mid -0.402042 -0.402042)
							(end -0.4318 -0.3302)
						)
						(arc
							(start -0.4318 0.3302)
							(mid -0.402042 0.402042)
							(end -0.3302 0.4318)
						)
						(arc
							(start 0.3302 0.4318)
							(mid 0.402042 0.402042)
							(end 0.4318 0.3302)
						)
						(arc
							(start 0.4318 -0.3302)
							(mid 0.402042 -0.402042)
							(end 0.3302 -0.4318)
						)
					)
					(width 0)
					(fill yes)
				)
			)
		)
		(pad "2" smd custom
			(at 0 0.762 180)
			(size 0.2159 0.2159)
			(layers "F.Cu" "F.Mask" "F.Paste")
			(net "GND")
			(options
				(clearance outline)
				(anchor circle)
			)
			(primitives
				(gr_poly
					(pts
						(arc
							(start -0.3302 -0.4318)
							(mid -0.402042 -0.402042)
							(end -0.4318 -0.3302)
						)
						(arc
							(start -0.4318 0.3302)
							(mid -0.402042 0.402042)
							(end -0.3302 0.4318)
						)
						(arc
							(start 0.3302 0.4318)
							(mid 0.402042 0.402042)
							(end 0.4318 0.3302)
						)
						(arc
							(start 0.4318 -0.3302)
							(mid 0.402042 -0.402042)
							(end 0.3302 -0.4318)
						)
					)
					(width 0)
					(fill yes)
				)
			)
		)
	)
	(footprint ""
		(layer "F.Cu")
		(at 158.663386 -158.660592 90)
		(property "Reference" "C247"
			(at 0 0 90)
			(layer "F.SilkS")
			(hide yes)
			(effects
				(font
					(size 1.27 1.27)
				)
			)
		)
		(property "Value" "SCD01U16V1KX-GP"
			(at -2.8321 -1.7399 90)
			(unlocked yes)
			(layer "F.Fab")
			(hide yes)
			(effects
				(font
					(size 1.016 1.016)
					(thickness 0.1524)
				)
			)
		)
		(property "Device Type" "C0201H13"
			(at -2.8321 -3.2639 90)
			(unlocked yes)
			(layer "F.Fab")
			(hide yes)
			(effects
				(font
					(size 1.016 1.016)
					(thickness 0.1524)
				)
			)
		)
		(duplicate_pad_numbers_are_jumpers no)
		(fp_rect
			(start -0.2794 0.6477)
			(end 0.2794 -0.6477)
			(stroke
				(width 0)
				(type default)
			)
			(fill no)
			(layer "F.CrtYd")
		)
		(fp_rect
			(start -0.2794 0.6477)
			(end 0.2794 -0.6477)
			(stroke
				(width 0)
				(type default)
			)
			(fill no)
			(layer "F.Fab")
		)
		(pad "1" smd custom
			(at 0 -0.2794 90)
			(size 0.0762 0.0762)
			(layers "F.Cu" "F.Mask" "F.Paste")
			(net "SAS_HDD_RX_P16")
			(options
				(clearance outline)
				(anchor circle)
			)
			(primitives
				(gr_poly
					(pts
						(arc
							(start 0.1524 -0.127)
							(mid 0.137521 -0.162921)
							(end 0.1016 -0.1778)
						)
						(arc
							(start -0.1016 -0.1778)
							(mid -0.137521 -0.162921)
							(end -0.1524 -0.127)
						)
						(arc
							(start -0.1524 0.127)
							(mid -0.137521 0.162921)
							(end -0.1016 0.1778)
						)
						(arc
							(start 0.1016 0.1778)
							(mid 0.137521 0.162921)
							(end 0.1524 0.127)
						)
					)
					(width 0)
					(fill yes)
				)
			)
		)
		(pad "2" smd custom
			(at 0 0.2794 90)
			(size 0.0762 0.0762)
			(layers "F.Cu" "F.Mask" "F.Paste")
			(net "PHY_SCC_A_TO_DRV_A_16_DP")
			(options
				(clearance outline)
				(anchor circle)
			)
			(primitives
				(gr_poly
					(pts
						(arc
							(start 0.1524 -0.127)
							(mid 0.137521 -0.162921)
							(end 0.1016 -0.1778)
						)
						(arc
							(start -0.1016 -0.1778)
							(mid -0.137521 -0.162921)
							(end -0.1524 -0.127)
						)
						(arc
							(start -0.1524 0.127)
							(mid -0.137521 0.162921)
							(end -0.1016 0.1778)
						)
						(arc
							(start 0.1016 0.1778)
							(mid 0.137521 0.162921)
							(end 0.1524 0.127)
						)
					)
					(width 0)
					(fill yes)
				)
			)
		)
	)
	(footprint ""
		(layer "F.Cu")
		(at 245.824502 -395.418564 180)
		(property "Reference" "C594"
			(at 0 0 180)
			(layer "F.SilkS")
			(hide yes)
			(effects
				(font
					(size 1.27 1.27)
				)
			)
		)
		(property "Value" "SC1U16V3KX-5GP"
			(at 0 -2.8194 180)
			(unlocked yes)
			(layer "F.Fab")
			(hide yes)
			(effects
				(font
					(size 1.016 1.016)
					(thickness 0.1524)
				)
			)
		)
		(property "Device Type" "C603H36"
			(at 0 -4.3434 180)
			(unlocked yes)
			(layer "F.Fab")
			(hide yes)
			(effects
				(font
					(size 1.016 1.016)
					(thickness 0.1524)
				)
			)
		)
		(duplicate_pad_numbers_are_jumpers no)
		(fp_line
			(start 0.508 0)
			(end -0.508 0)
			(stroke
				(width 0.2032)
				(type default)
			)
			(layer "F.SilkS")
		)
		(fp_rect
			(start -0.5842 1.3335)
			(end 0.5842 -1.3335)
			(stroke
				(width 0)
				(type default)
			)
			(fill no)
			(layer "F.CrtYd")
		)
		(fp_rect
			(start -0.5842 1.3335)
			(end 0.5842 -1.3335)
			(stroke
				(width 0)
				(type default)
			)
			(fill no)
			(layer "F.Fab")
		)
		(pad "1" smd custom
			(at 0 -0.762 180)
			(size 0.2159 0.2159)
			(layers "F.Cu" "F.Mask" "F.Paste")
			(net "MB3_CM_OV_R")
			(options
				(clearance outline)
				(anchor circle)
			)
			(primitives
				(gr_poly
					(pts
						(arc
							(start -0.3302 -0.4318)
							(mid -0.402042 -0.402042)
							(end -0.4318 -0.3302)
						)
						(arc
							(start -0.4318 0.3302)
							(mid -0.402042 0.402042)
							(end -0.3302 0.4318)
						)
						(arc
							(start 0.3302 0.4318)
							(mid 0.402042 0.402042)
							(end 0.4318 0.3302)
						)
						(arc
							(start 0.4318 -0.3302)
							(mid 0.402042 -0.402042)
							(end 0.3302 -0.4318)
						)
					)
					(width 0)
					(fill yes)
				)
			)
		)
		(pad "2" smd custom
			(at 0 0.762 180)
			(size 0.2159 0.2159)
			(layers "F.Cu" "F.Mask" "F.Paste")
			(net "AGND_CURRENT_DPB")
			(options
				(clearance outline)
				(anchor circle)
			)
			(primitives
				(gr_poly
					(pts
						(arc
							(start -0.3302 -0.4318)
							(mid -0.402042 -0.402042)
							(end -0.4318 -0.3302)
						)
						(arc
							(start -0.4318 0.3302)
							(mid -0.402042 0.402042)
							(end -0.3302 0.4318)
						)
						(arc
							(start 0.3302 0.4318)
							(mid 0.402042 0.402042)
							(end 0.4318 0.3302)
						)
						(arc
							(start 0.4318 -0.3302)
							(mid 0.402042 -0.402042)
							(end 0.3302 -0.4318)
						)
					)
					(width 0)
					(fill yes)
				)
			)
		)
	)
	(footprint ""
		(layer "F.Cu")
		(at 247.849898 6.49986)
		(property "Reference" ""
			(at 0 0 0)
			(layer "F.SilkS")
			(hide yes)
			(effects
				(font
					(size 1.27 1.27)
				)
			)
		)
		(property "Value" "*"
			(at -5.5499 1.3716 0)
			(unlocked yes)
			(layer "F.Fab")
			(hide yes)
			(effects
				(font
					(size 1.016 1.016)
					(thickness 0.1524)
				)
			)
		)
		(duplicate_pad_numbers_are_jumpers no)
		(fp_poly
			(pts
				(arc
					(start 4.064 0)
					(mid -4.064 0)
					(end 4.064 0)
				)
			)
			(stroke
				(width 0)
				(type default)
			)
			(fill no)
			(layer "B.CrtYd")
		)
		(fp_poly
			(pts
				(arc
					(start 4.064 0)
					(mid -4.064 0)
					(end 4.064 0)
				)
			)
			(stroke
				(width 0)
				(type default)
			)
			(fill no)
			(layer "F.CrtYd")
		)
		(fp_poly
			(pts
				(arc
					(start 4.064 0)
					(mid -4.064 0)
					(end 4.064 0)
				)
			)
			(stroke
				(width 0)
				(type default)
			)
			(fill no)
			(layer "B.Fab")
		)
		(fp_poly
			(pts
				(arc
					(start 4.064 0)
					(mid -4.064 0)
					(end 4.064 0)
				)
			)
			(stroke
				(width 0)
				(type default)
			)
			(fill no)
			(layer "F.Fab")
		)
		(pad "1" thru_hole circle
			(at 0 0)
			(size 7.5184 7.5184)
			(drill oval 5.0038 3.0226)
			(layers "*.Cu" "*.Mask")
			(remove_unused_layers no)
			(net "Net_33")
			(clearance -1.7399)
			(thermal_gap 0.1524)
			(padstack
				(mode front_inner_back)
				(layer "Inner"
					(shape oval)
					(size 3.7338 5.715)
					(clearance 0.1524)
				)
				(layer "B.Cu"
					(shape circle)
					(size 7.5184 7.5184)
					(clearance -1.7399)
				)
			)
		)
		(zone
			(layers "F.Cu" "B.Cu" "In1.Cu" "In2.Cu" "In3.Cu" "In4.Cu" "In5.Cu" "In6.Cu"
				"In7.Cu" "In8.Cu" "In9.Cu" "In10.Cu"
			)
			(hatch none 0.5)
			(connect_pads
				(clearance 0)
			)
			(min_thickness 0.25)
			(keepout
				(tracks not_allowed)
				(vias allowed)
				(pads allowed)
				(copperpour not_allowed)
				(footprints allowed)
			)
			(placement
				(enabled no)
				(sheetname "")
			)
			(fill
				(thermal_gap 0.5)
				(thermal_bridge_width 0.5)
				(island_removal_mode 0)
			)
			(polygon
				(pts
					(arc
						(start 251.609098 6.49986)
						(mid 244.090698 6.49986)
						(end 251.609098 6.49986)
					)
				)
			)
		)
	)
	(footprint ""
		(layer "F.Cu")
		(at 381.2286 -67.4624)
		(property "Reference" "TP162"
			(at 0 0 0)
			(layer "F.SilkS")
			(hide yes)
			(effects
				(font
					(size 1.27 1.27)
				)
			)
		)
		(property "Value" "TPAD32-GP"
			(at -0.0508 -1.6764 0)
			(unlocked yes)
			(layer "F.Fab")
			(hide yes)
			(effects
				(font
					(size 1.016 1.016)
					(thickness 0.1524)
				)
			)
		)
		(property "Device Type" "TPAD32"
			(at -0.0508 -3.2004 0)
			(unlocked yes)
			(layer "F.Fab")
			(hide yes)
			(effects
				(font
					(size 1.016 1.016)
					(thickness 0.1524)
				)
			)
		)
		(duplicate_pad_numbers_are_jumpers no)
		(fp_poly
			(pts
				(arc
					(start 0.4064 0)
					(mid -0.4064 0)
					(end 0.4064 0)
				)
			)
			(stroke
				(width 0)
				(type default)
			)
			(fill no)
			(layer "F.CrtYd")
		)
		(fp_poly
			(pts
				(arc
					(start 0.7112 0)
					(mid -0.7112 0)
					(end 0.7112 0)
				)
			)
			(stroke
				(width 0)
				(type default)
			)
			(fill no)
			(layer "F.Fab")
		)
		(pad "1" smd circle
			(at 0 0)
			(size 0.8128 0.8128)
			(layers "F.Cu" "F.Mask" "F.Paste")
			(net "ACT_HDD_32")
		)
	)
	(footprint ""
		(layer "F.Cu")
		(at 282.351734 21.726652 -90)
		(property "Reference" "R1136"
			(at 0 0 270)
			(layer "F.SilkS")
			(hide yes)
			(effects
				(font
					(size 1.27 1.27)
				)
			)
		)
		(property "Value" "10KR2F-2-GP"
			(at 0.064008 -3.993896 270)
			(unlocked yes)
			(layer "F.Fab")
			(hide yes)
			(effects
				(font
					(size 1.016 1.016)
					(thickness 0.1524)
				)
			)
		)
		(property "Device Type" "R402H16"
			(at 0.064008 -5.517896 270)
			(unlocked yes)
			(layer "F.Fab")
			(hide yes)
			(effects
				(font
					(size 1.016 1.016)
					(thickness 0.1524)
				)
			)
		)
		(duplicate_pad_numbers_are_jumpers no)
		(fp_line
			(start -0.508 -0.9398)
			(end -0.508 0.9398)
			(stroke
				(width 0.1524)
				(type default)
			)
			(layer "F.SilkS")
		)
		(fp_line
			(start 0.508 -0.9398)
			(end -0.508 -0.9398)
			(stroke
				(width 0.1524)
				(type default)
			)
			(layer "F.SilkS")
		)
		(fp_rect
			(start -0.508 0.9398)
			(end 0.508 -0.9398)
			(stroke
				(width 0)
				(type default)
			)
			(fill no)
			(layer "F.CrtYd")
		)
		(fp_rect
			(start -0.508 0.9398)
			(end 0.508 -0.9398)
			(stroke
				(width 0)
				(type default)
			)
			(fill no)
			(layer "F.Fab")
		)
		(pad "1" smd custom
			(at 0 -0.4445 270)
			(size 0.1397 0.1397)
			(layers "F.Cu" "F.Mask" "F.Paste")
			(net "P12V_IN")
			(options
				(clearance outline)
				(anchor circle)
			)
			(primitives
				(gr_poly
					(pts
						(arc
							(start -0.1778 -0.2794)
							(mid -0.249642 -0.249642)
							(end -0.2794 -0.1778)
						)
						(arc
							(start -0.2794 0.1778)
							(mid -0.249642 0.249642)
							(end -0.1778 0.2794)
						)
						(arc
							(start 0.1778 0.2794)
							(mid 0.249642 0.249642)
							(end 0.2794 0.1778)
						)
						(arc
							(start 0.2794 -0.1778)
							(mid 0.249642 -0.249642)
							(end 0.1778 -0.2794)
						)
					)
					(width 0)
					(fill yes)
				)
			)
		)
		(pad "2" smd custom
			(at 0 0.4445 270)
			(size 0.1397 0.1397)
			(layers "F.Cu" "F.Mask" "F.Paste")
			(net "DPB_PWR_BTN_B")
			(options
				(clearance outline)
				(anchor circle)
			)
			(primitives
				(gr_poly
					(pts
						(arc
							(start -0.1778 -0.2794)
							(mid -0.249642 -0.249642)
							(end -0.2794 -0.1778)
						)
						(arc
							(start -0.2794 0.1778)
							(mid -0.249642 0.249642)
							(end -0.1778 0.2794)
						)
						(arc
							(start 0.1778 0.2794)
							(mid 0.249642 0.249642)
							(end 0.2794 0.1778)
						)
						(arc
							(start 0.2794 -0.1778)
							(mid 0.249642 -0.249642)
							(end 0.1778 -0.2794)
						)
					)
					(width 0)
					(fill yes)
				)
			)
		)
	)
	(footprint ""
		(layer "F.Cu")
		(at 14.817598 -160.608518 90)
		(property "Reference" "R420"
			(at 0 0 90)
			(layer "F.SilkS")
			(hide yes)
			(effects
				(font
					(size 1.27 1.27)
				)
			)
		)
		(property "Value" "4K7R2J-2-GP"
			(at 0.064008 -3.993896 90)
			(unlocked yes)
			(layer "F.Fab")
			(hide yes)
			(effects
				(font
					(size 1.016 1.016)
					(thickness 0.1524)
				)
			)
		)
		(property "Device Type" "R402H16"
			(at 0.064008 -5.517896 90)
			(unlocked yes)
			(layer "F.Fab")
			(hide yes)
			(effects
				(font
					(size 1.016 1.016)
					(thickness 0.1524)
				)
			)
		)
		(duplicate_pad_numbers_are_jumpers no)
		(fp_line
			(start 0.508 -0.9398)
			(end -0.508 -0.9398)
			(stroke
				(width 0.1524)
				(type default)
			)
			(layer "F.SilkS")
		)
		(fp_line
			(start -0.508 -0.9398)
			(end -0.508 0.9398)
			(stroke
				(width 0.1524)
				(type default)
			)
			(layer "F.SilkS")
		)
		(fp_rect
			(start -0.508 0.9398)
			(end 0.508 -0.9398)
			(stroke
				(width 0)
				(type default)
			)
			(fill no)
			(layer "F.CrtYd")
		)
		(fp_rect
			(start -0.508 0.9398)
			(end 0.508 -0.9398)
			(stroke
				(width 0)
				(type default)
			)
			(fill no)
			(layer "F.Fab")
		)
		(pad "1" smd custom
			(at 0 -0.4445 90)
			(size 0.1397 0.1397)
			(layers "F.Cu" "F.Mask" "F.Paste")
			(net "P12V_A")
			(options
				(clearance outline)
				(anchor circle)
			)
			(primitives
				(gr_poly
					(pts
						(arc
							(start -0.1778 -0.2794)
							(mid -0.249642 -0.249642)
							(end -0.2794 -0.1778)
						)
						(arc
							(start -0.2794 0.1778)
							(mid -0.249642 0.249642)
							(end -0.1778 0.2794)
						)
						(arc
							(start 0.1778 0.2794)
							(mid 0.249642 0.249642)
							(end 0.2794 0.1778)
						)
						(arc
							(start 0.2794 -0.1778)
							(mid 0.249642 -0.249642)
							(end 0.1778 -0.2794)
						)
					)
					(width 0)
					(fill yes)
				)
			)
		)
		(pad "2" smd custom
			(at 0 0.4445 90)
			(size 0.1397 0.1397)
			(layers "F.Cu" "F.Mask" "F.Paste")
			(net "SW_HDD_R12")
			(options
				(clearance outline)
				(anchor circle)
			)
			(primitives
				(gr_poly
					(pts
						(arc
							(start -0.1778 -0.2794)
							(mid -0.249642 -0.249642)
							(end -0.2794 -0.1778)
						)
						(arc
							(start -0.2794 0.1778)
							(mid -0.249642 0.249642)
							(end -0.1778 0.2794)
						)
						(arc
							(start 0.1778 0.2794)
							(mid 0.249642 0.249642)
							(end 0.2794 0.1778)
						)
						(arc
							(start 0.2794 -0.1778)
							(mid 0.249642 -0.249642)
							(end 0.1778 -0.2794)
						)
					)
					(width 0)
					(fill yes)
				)
			)
		)
	)
)
